# BASEBOARD_FAB2 (Tioga Pass) — schematic netlist excerpt (pin names and nets, part order shuffled) for the footprints in the layout excerpt that follows; sources: Cadence DE-HDL packaged netlist, KiCad conversion of Wiwynn_Tioga_Pass_MB.brd

EU1B1  PXM1310B  IC  pkg QFN  page 226
  BPWM1  = NC
  DNC(0)  = NC
  APWM3  = NC
  APWM2  = VR_PVDDQ_KLM_PWM2
  APWM1  = VR_PVDDQ_KLM_PWM1
  SDA  = SMB_VR_STBY_LVC3_SDA
  SCL  = SMB_VR_STBY_LVC3_SCL
  RESET_N  = NC
  AVRRDY  = PWRGD_PVDDQ_KLM_R
  AVREN  = VR_PVDDQ_KLM_VREN
  VRHOT_N  = IRQ_PVDDQ_KLM_VRHOT_LVT3_R_N
  PINALRT_N  = NC
  MP0  = PU_VR_PVDDQ_KLM_FAULT1
  MP1  = NC_PVDDQ_KLM_GP1
  VCLK  = SVID_CLK_PVDDQ_KLM
  VDIO  = SVID_VDIO_PVDDQ_KLM
  VALRT_N  = SVID_ALERT_PVDDQ_KLM
  MP2  = NC_PVDDQ_KLM_GP0
  AVSEN  = VR_PVDDQ_KLM_AVSP
  AVREF  = VSENSE_PVDDQ_KLM_N
  AIREF1  = VR_PVDDQ_KLM_AIREF1
  AISEN1  = ISENSE_PVDDQ_KLM_PH1_IMON
  AIREF2  = VR_PVDDQ_KLM_AIREF2
  AISEN2  = ISENSE_PVDDQ_KLM_PH2_IMON
  AIREF3  = NC
  AISEN3  = NC
  GND  = GND
  DNC(1)  = NC
  BVSEN  = NC
  BVREF  = NC
  BIREF1  = NC
  BISEN1  = GND
  XADDR2  = VR_PVDDQ_KLM_XADDR2
  BTSEN  = NC
  ATSEN  = A_TSENSE_PVDDQ_KLM
  XADDR1  = VR_PVDDQ_KLM_XADDR1
  VINSEN  = VR_PVDDQ_KLM_VINSEN
  IINSEN  = VR_PVDDQ_KLM_AIINSEN
  VDD  = VR_PVDDQ_KLM_VDD
  VD12  = VR_PVDDQ_KLM_VD12
  THPAD  = GND

(kicad_pcb
	(version 20260206)
	(generator "pcbnew")
	(generator_version "10.0")
	(general
		(thickness 1.6)
		(legacy_teardrops no)
	)
	(paper "A4")
	(title_block
		(title "Wiwynn_Tioga_Pass_MB.brd")
		(comment 1 "Tioga Pass / footprint 1727 of 4770 (EU1B1), pads 18-34 of 41")
	)
	(layers
		(0 "F.Cu" signal "TOP")
		(4 "In1.Cu" signal "L2GND")
		(6 "In2.Cu" signal "L3")
		(8 "In3.Cu" signal "L4GND")
		(10 "In4.Cu" signal "L5")
		(12 "In5.Cu" signal "L6GND")
		(14 "In6.Cu" signal "L7VCC")
		(16 "In7.Cu" signal "L8VCC")
		(18 "In8.Cu" signal "L9GND")
		(20 "In9.Cu" signal "L10")
		(22 "In10.Cu" signal "L11GND")
		(24 "In11.Cu" signal "L12")
		(26 "In12.Cu" signal "L13GND")
		(2 "B.Cu" signal "BOTTOM")
		(9 "F.Adhes" user "F.Adhesive")
		(11 "B.Adhes" user "B.Adhesive")
		(13 "F.Paste" user "Package Geometry/Pastemask Top")
		(15 "B.Paste" user "Package Geometry/Pastemask Bottom")
		(5 "F.SilkS" user "Ref Des/Silkscreen Top")
		(7 "B.SilkS" user "Ref Des/Silkscreen Bottom")
		(1 "F.Mask" user "Board Geometry/Soldermask Top")
		(3 "B.Mask" user "Board Geometry/Soldermask Bottom")
		(17 "Dwgs.User" user "User.Drawings")
		(19 "Cmts.User" user "User.Comments")
		(21 "Eco1.User" user "User.Eco1")
		(23 "Eco2.User" user "User.Eco2")
		(25 "Edge.Cuts" user "Board Geometry/Outline")
		(27 "Margin" user)
		(31 "F.CrtYd" user "Package Geometry/Place Bound Top")
		(29 "B.CrtYd" user "Package Geometry/Place Bound Bottom")
		(35 "F.Fab" user "Ref Des/Assembly Top")
		(33 "B.Fab" user "Ref Des/Assembly Bottom")
	)
	(footprint ""
		(layer "F.Cu")
		(at 2.0574 -127.9652 -90)
		(property "Reference" "EU1B1"
			(at 3.76047 4.0132 0)
			(unlocked yes)
			(layer "F.SilkS")
			(effects
				(font
					(size 0.7874 0.5842)
					(thickness 0.1524)
				)
				(justify left)
			)
		)
		(property "Value" ""
			(at 0 0 270)
			(layer "F.Fab")
			(effects
				(font
					(size 1.27 1.27)
				)
			)
		)
		(duplicate_pad_numbers_are_jumpers no)
		(pad "18" smd custom
			(at 0.999998 2.4511 270)
			(size 0.0508 0.0508)
			(layers "F.Cu" "F.Mask" "F.Paste")
			(net "NC_PVDDQ_KLM_GP0")
			(options
				(clearance outline)
				(anchor circle)
			)
			(primitives
				(gr_poly
					(pts
						(arc
							(start -0.1016 -0.254)
							(mid 0 -0.3556)
							(end 0.1016 -0.254)
						)
						(xy 0.1016 0.3556) (xy -0.1016 0.3556)
					)
					(width 0)
					(fill yes)
				)
			)
		)
		(pad "19" smd custom
			(at 1.400048 2.4511 270)
			(size 0.0508 0.0508)
			(layers "F.Cu" "F.Mask" "F.Paste")
			(net "VR_PVDDQ_KLM_AVSP")
			(options
				(clearance outline)
				(anchor circle)
			)
			(primitives
				(gr_poly
					(pts
						(arc
							(start -0.1016 -0.254)
							(mid 0 -0.3556)
							(end 0.1016 -0.254)
						)
						(xy 0.1016 0.3556) (xy -0.1016 0.3556)
					)
					(width 0)
					(fill yes)
				)
			)
		)
		(pad "20" smd custom
			(at 1.800098 2.4511 270)
			(size 0.0508 0.0508)
			(layers "F.Cu" "F.Mask" "F.Paste")
			(net "VSENSE_PVDDQ_KLM_N")
			(options
				(clearance outline)
				(anchor circle)
			)
			(primitives
				(gr_poly
					(pts
						(arc
							(start -0.1016 -0.254)
							(mid 0 -0.3556)
							(end 0.1016 -0.254)
						)
						(xy 0.1016 0.3556) (xy -0.1016 0.3556)
					)
					(width 0)
					(fill yes)
				)
			)
		)
		(pad "21" smd custom
			(at 2.4511 1.800098 270)
			(size 0.0508 0.0508)
			(layers "F.Cu" "F.Mask" "F.Paste")
			(net "VR_PVDDQ_KLM_AIREF1")
			(options
				(clearance outline)
				(anchor circle)
			)
			(primitives
				(gr_poly
					(pts
						(arc
							(start -0.254 0.1016)
							(mid -0.3556 0)
							(end -0.254 -0.1016)
						)
						(xy 0.3556 -0.1016) (xy 0.3556 0.1016)
					)
					(width 0)
					(fill yes)
				)
			)
		)
		(pad "22" smd custom
			(at 2.4511 1.400048 270)
			(size 0.0508 0.0508)
			(layers "F.Cu" "F.Mask" "F.Paste")
			(net "ISENSE_PVDDQ_KLM_PH1_IMON")
			(options
				(clearance outline)
				(anchor circle)
			)
			(primitives
				(gr_poly
					(pts
						(arc
							(start -0.254 0.1016)
							(mid -0.3556 0)
							(end -0.254 -0.1016)
						)
						(xy 0.3556 -0.1016) (xy 0.3556 0.1016)
					)
					(width 0)
					(fill yes)
				)
			)
		)
		(pad "23" smd custom
			(at 2.4511 0.999998 270)
			(size 0.0508 0.0508)
			(layers "F.Cu" "F.Mask" "F.Paste")
			(net "VR_PVDDQ_KLM_AIREF2")
			(options
				(clearance outline)
				(anchor circle)
			)
			(primitives
				(gr_poly
					(pts
						(arc
							(start -0.254 0.1016)
							(mid -0.3556 0)
							(end -0.254 -0.1016)
						)
						(xy 0.3556 -0.1016) (xy 0.3556 0.1016)
					)
					(width 0)
					(fill yes)
				)
			)
		)
		(pad "24" smd custom
			(at 2.4511 0.599948 270)
			(size 0.0508 0.0508)
			(layers "F.Cu" "F.Mask" "F.Paste")
			(net "ISENSE_PVDDQ_KLM_PH2_IMON")
			(options
				(clearance outline)
				(anchor circle)
			)
			(primitives
				(gr_poly
					(pts
						(arc
							(start -0.254 0.1016)
							(mid -0.3556 0)
							(end -0.254 -0.1016)
						)
						(xy 0.3556 -0.1016) (xy 0.3556 0.1016)
					)
					(width 0)
					(fill yes)
				)
			)
		)
		(pad "25" smd custom
			(at 2.4511 0.199898 270)
			(size 0.0508 0.0508)
			(layers "F.Cu" "F.Mask" "F.Paste")
			(net "Net_249")
			(options
				(clearance outline)
				(anchor circle)
			)
			(primitives
				(gr_poly
					(pts
						(arc
							(start -0.254 0.1016)
							(mid -0.3556 0)
							(end -0.254 -0.1016)
						)
						(xy 0.3556 -0.1016) (xy 0.3556 0.1016)
					)
					(width 0)
					(fill yes)
				)
			)
		)
		(pad "26" smd custom
			(at 2.4511 -0.199898 270)
			(size 0.0508 0.0508)
			(layers "F.Cu" "F.Mask" "F.Paste")
			(net "Net_248")
			(options
				(clearance outline)
				(anchor circle)
			)
			(primitives
				(gr_poly
					(pts
						(arc
							(start -0.254 0.1016)
							(mid -0.3556 0)
							(end -0.254 -0.1016)
						)
						(xy 0.3556 -0.1016) (xy 0.3556 0.1016)
					)
					(width 0)
					(fill yes)
				)
			)
		)
		(pad "27" smd custom
			(at 2.4511 -0.599948 270)
			(size 0.0508 0.0508)
			(layers "F.Cu" "F.Mask" "F.Paste")
			(net "GND")
			(options
				(clearance outline)
				(anchor circle)
			)
			(primitives
				(gr_poly
					(pts
						(arc
							(start -0.254 0.1016)
							(mid -0.3556 0)
							(end -0.254 -0.1016)
						)
						(xy 0.3556 -0.1016) (xy 0.3556 0.1016)
					)
					(width 0)
					(fill yes)
				)
			)
		)
		(pad "28" smd custom
			(at 2.4511 -0.999998 270)
			(size 0.0508 0.0508)
			(layers "F.Cu" "F.Mask" "F.Paste")
			(net "Net_272")
			(options
				(clearance outline)
				(anchor circle)
			)
			(primitives
				(gr_poly
					(pts
						(arc
							(start -0.254 0.1016)
							(mid -0.3556 0)
							(end -0.254 -0.1016)
						)
						(xy 0.3556 -0.1016) (xy 0.3556 0.1016)
					)
					(width 0)
					(fill yes)
				)
			)
		)
		(pad "29" smd custom
			(at 2.4511 -1.400048 270)
			(size 0.0508 0.0508)
			(layers "F.Cu" "F.Mask" "F.Paste")
			(net "Net_238")
			(options
				(clearance outline)
				(anchor circle)
			)
			(primitives
				(gr_poly
					(pts
						(arc
							(start -0.254 0.1016)
							(mid -0.3556 0)
							(end -0.254 -0.1016)
						)
						(xy 0.3556 -0.1016) (xy 0.3556 0.1016)
					)
					(width 0)
					(fill yes)
				)
			)
		)
		(pad "30" smd custom
			(at 2.4511 -1.800098 270)
			(size 0.0508 0.0508)
			(layers "F.Cu" "F.Mask" "F.Paste")
			(net "Net_237")
			(options
				(clearance outline)
				(anchor circle)
			)
			(primitives
				(gr_poly
					(pts
						(arc
							(start -0.254 0.1016)
							(mid -0.3556 0)
							(end -0.254 -0.1016)
						)
						(xy 0.3556 -0.1016) (xy 0.3556 0.1016)
					)
					(width 0)
					(fill yes)
				)
			)
		)
		(pad "31" smd custom
			(at 1.800098 -2.4511 270)
			(size 0.0508 0.0508)
			(layers "F.Cu" "F.Mask" "F.Paste")
			(net "Net_235")
			(options
				(clearance outline)
				(anchor circle)
			)
			(primitives
				(gr_poly
					(pts
						(arc
							(start 0.1016 0.254)
							(mid 0 0.3556)
							(end -0.1016 0.254)
						)
						(xy -0.1016 -0.3556) (xy 0.1016 -0.3556)
					)
					(width 0)
					(fill yes)
				)
			)
		)
		(pad "32" smd custom
			(at 1.400048 -2.4511 270)
			(size 0.0508 0.0508)
			(layers "F.Cu" "F.Mask" "F.Paste")
			(net "GND")
			(options
				(clearance outline)
				(anchor circle)
			)
			(primitives
				(gr_poly
					(pts
						(arc
							(start 0.1016 0.254)
							(mid 0 0.3556)
							(end -0.1016 0.254)
						)
						(xy -0.1016 -0.3556) (xy 0.1016 -0.3556)
					)
					(width 0)
					(fill yes)
				)
			)
		)
		(pad "33" smd custom
			(at 0.999998 -2.4511 270)
			(size 0.0508 0.0508)
			(layers "F.Cu" "F.Mask" "F.Paste")
			(net "VR_PVDDQ_KLM_XADDR2")
			(options
				(clearance outline)
				(anchor circle)
			)
			(primitives
				(gr_poly
					(pts
						(arc
							(start 0.1016 0.254)
							(mid 0 0.3556)
							(end -0.1016 0.254)
						)
						(xy -0.1016 -0.3556) (xy 0.1016 -0.3556)
					)
					(width 0)
					(fill yes)
				)
			)
		)
		(pad "34" smd custom
			(at 0.599948 -2.4511 270)
			(size 0.0508 0.0508)
			(layers "F.Cu" "F.Mask" "F.Paste")
			(net "Net_236")
			(options
				(clearance outline)
				(anchor circle)
			)
			(primitives
				(gr_poly
					(pts
						(arc
							(start 0.1016 0.254)
							(mid 0 0.3556)
							(end -0.1016 0.254)
						)
						(xy -0.1016 -0.3556) (xy 0.1016 -0.3556)
					)
					(width 0)
					(fill yes)
				)
			)
		)
	)
)
